# S9S_MB_2U (Grand Teton) — schematic netlist excerpt (pin names and nets, part order shuffled) for the footprints in the layout excerpt that follows; sources: Cadence DE-HDL packaged netlist, KiCad conversion of 03242023_DA0F0TMBIJ0_F0T_Motherboard_J_brd_V01_OCP.brd

J2  SCONN288_ADR50017P087CC  SCONN288_ADR50017-P087CC IO  pkg DDR288S_1-1VXB  page 83
  VIN_BULK0  = P12V_S3_AUX_CPU0_NVDIMM
  RFU0  = TP_CHA_CPU0_DIMM2_FRU_0
  VIN_MGMT  = P3V3_AUX
  HSCL  = I3C_SPD_DDRABCD_CPU0_LVC1_SCL_1
  HSDA  = I3C_SPD_DDRABCD_CPU0_LVC1_SDA
  VSS0  = GND
  DQ0_A  = M_A_CPU0_SA_DQ<0>
  VSS1  = GND
  DQ1_A  = M_A_CPU0_SA_DQ<1>
  VSS2  = GND
  DQS0_A_T  = M_A_CPU0_SA_DQS_DP<0>
  DQS0_A_C  = M_A_CPU0_SA_DQS_DN<0>
  VSS3  = GND
  DQ4_A  = M_A_CPU0_SA_DQ<4>
  VSS4  = GND
  DQ5_A  = M_A_CPU0_SA_DQ<5>
  VSS5  = GND
  DQ8_A  = M_A_CPU0_SA_DQ<8>
  VSS6  = GND
  DQ9_A  = M_A_CPU0_SA_DQ<9>
  VSS7  = GND
  DQS1_A_T  = M_A_CPU0_SA_DQS_DP<1>
  DQS1_A_C  = M_A_CPU0_SA_DQS_DN<1>
  VSS8  = GND
  DQ12_A  = M_A_CPU0_SA_DQ<12>
  VSS9  = GND
  DQ13_A  = M_A_CPU0_SA_DQ<13>
  VSS10  = GND
  DQ16_A  = M_A_CPU0_SA_DQ<16>
  VSS11  = GND
  DQ17_A  = M_A_CPU0_SA_DQ<17>
  VSS12  = GND
  DQS2_A_T  = M_A_CPU0_SA_DQS_DP<2>
  DQS2_A_C  = M_A_CPU0_SA_DQS_DN<2>
  VSS13  = GND
  DQ20_A  = M_A_CPU0_SA_DQ<20>
  VSS14  = GND
  DQ21_A  = M_A_CPU0_SA_DQ<21>
  VSS15  = GND
  DQ24_A  = M_A_CPU0_SA_DQ<24>
  VSS16  = GND
  DQ25_A  = M_A_CPU0_SA_DQ<25>
  VSS17  = GND
  DQS3_A_T  = M_A_CPU0_SA_DQS_DP<3>
  DQS3_A_C  = M_A_CPU0_SA_DQS_DN<3>
  VSS18  = GND
  DQ28_A  = M_A_CPU0_SA_DQ<28>
  VSS19  = GND
  DQ29_A  = M_A_CPU0_SA_DQ<29>
  VSS20  = GND
  CB0_A  = M_A_CPU0_SA_CB<0>
  VSS21  = GND
  CB1_A  = M_A_CPU0_SA_CB<1>
  VSS22  = GND
  DQS4_A_T  = M_A_CPU0_SA_DQS_DP<4>
  DQS4_A_C  = M_A_CPU0_SA_DQS_DN<4>
  VSS23  = GND
  CB4_A  = M_A_CPU0_SA_CB<4>
  VSS24  = GND
  CB5_A  = M_A_CPU0_SA_CB<5>
  VSS25  = GND
  ALERT_N  = M_A_CPU0_ALERT_N
  VSS26  = GND
  CS0_A_N  = M_A_CPU0_SA_CS_N<2>
  VSS27  = GND
  CA0_A  = M_A_CPU0_SA_CA<0>
  VSS28  = GND
  CA2_A  = M_A_CPU0_SA_CA<2>
  VSS29  = GND
  CA4_A  = M_A_CPU0_SA_CA<4>
  VSS30  = GND
  CA6_A  = M_A_CPU0_SA_CA<6>
  VSS31  = GND
  PAR_A  = M_A_CPU0_SA_PAR
  VSS32  = GND
  CA0_B  = M_A_CPU0_SB_CA<0>
  VSS33  = GND
  CA2_B  = M_A_CPU0_SB_CA<2>
  VSS34  = GND
  CA4_B  = M_A_CPU0_SB_CA<4>
  VSS35  = GND
  CA6_B  = M_A_CPU0_SB_CA<6>
  VSS36  = GND
  CS0_B_N  = M_A_CPU0_SB_CS_N<2>
  VSS37  = GND
  \lbd||rsp_a_n\  = M_A_CPU0_SA_RSP<1>
  \lbs||rsp_b_n\  = M_A_CPU0_SB_RSP<1>
  VSS38  = GND
  CB4_B  = M_A_CPU0_SB_CB<4>
  VSS39  = GND
  CB5_B  = M_A_CPU0_SB_CB<5>
  VSS40  = GND
  \dqs9_b_t||tdqs9_b_t||dbi4_b_n\  = M_A_CPU0_SB_DQS_DP<9>
  \dqs9_b_c||tdqs9_b_c\  = M_A_CPU0_SB_DQS_DN<9>
  VSS41  = GND
  CB0_B  = M_A_CPU0_SB_CB<0>
  VSS42  = GND
  CB1_B  = M_A_CPU0_SB_CB<1>
  VSS43  = GND
  DQ0_B  = M_A_CPU0_SB_DQ<0>
  VSS44  = GND
  DQ1_B  = M_A_CPU0_SB_DQ<1>
  VSS45  = GND
  DQS0_B_T  = M_A_CPU0_SB_DQS_DP<0>
  DQS0_B_C  = M_A_CPU0_SB_DQS_DN<0>
  VSS46  = GND
  DQ4_B  = M_A_CPU0_SB_DQ<4>
  VSS47  = GND
  DQ5_B  = M_A_CPU0_SB_DQ<5>
  VSS48  = GND
  DQ8_B  = M_A_CPU0_SB_DQ<8>
  VSS49  = GND
  DQ9_B  = M_A_CPU0_SB_DQ<9>
  VSS50  = GND
  DQS1_B_T  = M_A_CPU0_SB_DQS_DP<1>
  DQS1_B_C  = M_A_CPU0_SB_DQS_DN<1>
  VSS51  = GND
  DQ12_B  = M_A_CPU0_SB_DQ<12>
  VSS52  = GND
  DQ13_B  = M_A_CPU0_SB_DQ<13>
  VSS53  = GND
  DQ16_B  = M_A_CPU0_SB_DQ<16>
  VSS54  = GND
  DQ17_B  = M_A_CPU0_SB_DQ<17>
  VSS55  = GND
  DQS2_B_T  = M_A_CPU0_SB_DQS_DP<2>
  DQS2_B_C  = M_A_CPU0_SB_DQS_DN<2>
  VSS56  = GND
  DQ20_B  = M_A_CPU0_SB_DQ<20>
  VSS57  = GND
  DQ21_B  = M_A_CPU0_SB_DQ<21>
  VSS58  = GND
  DQ24_B  = M_A_CPU0_SB_DQ<24>
  VSS59  = GND
  DQ25_B  = M_A_CPU0_SB_DQ<25>
  VSS60  = GND
  DQS3_B_T  = M_A_CPU0_SB_DQS_DP<3>
  DQS3_B_C  = M_A_CPU0_SB_DQS_DN<3>
  VSS61  = GND
  DQ28_B  = M_A_CPU0_SB_DQ<28>
  VSS62  = GND
  DQ29_B  = M_A_CPU0_SB_DQ<29>
  VSS63  = GND
  RFU1  = TP_CHA_CPU0_DIMM2_FRU_1
  VIN_BULK1  = P12V_S3_AUX_CPU0_NVDIMM
  VIN_BULK2  = P12V_S3_AUX_CPU0_NVDIMM
  \pwr_good||fail_n\  = PWRGD_CHA_CPU0_DIMM2
  HSA  = PD_CHA_CPU0_DIMM2_SAA
  RFU2  = TP_CHA_CPU0_DIMM2_FRU_2
  RFU3  = TP_CHA_CPU0_DIMM2_FRU_3
  VSS64  = GND
  DQ2_A  = M_A_CPU0_SA_DQ<2>
  VSS65  = GND
  DQ3_A  = M_A_CPU0_SA_DQ<3>
  VSS66  = GND
  \dqs5_a_c||tdqs5_a_c||dqs5_a_t||tdqs5_a_t\  = M_A_CPU0_SA_DQS_DN<5>
  \dqs5_a_t||tdqs5_a_t\  = M_A_CPU0_SA_DQS_DP<5>
  VSS67  = GND
  DQ6_A  = M_A_CPU0_SA_DQ<6>
  VSS68  = GND
  DQ7_A  = M_A_CPU0_SA_DQ<7>
  VSS69  = GND
  DQ10_A  = M_A_CPU0_SA_DQ<10>
  VSS70  = GND
  DQ11_A  = M_A_CPU0_SA_DQ<11>
  VSS71  = GND
  \dqs6_a_c||tdqs6_a_c||dqs6_a_t||tdqs6_a_t\  = M_A_CPU0_SA_DQS_DN<6>
  \dqs6_a_t||tdqs6_a_t\  = M_A_CPU0_SA_DQS_DP<6>
  VSS72  = GND
  DQ14_A  = M_A_CPU0_SA_DQ<14>
  VSS73  = GND
  DQ15_A  = M_A_CPU0_SA_DQ<15>
  VSS74  = GND
  DQ18_A  = M_A_CPU0_SA_DQ<18>
  VSS75  = GND
  DQ19_A  = M_A_CPU0_SA_DQ<19>
  VSS76  = GND
  \dqs7_a_c||tdqs7_a_c\  = M_A_CPU0_SA_DQS_DN<7>
  \dqs7_a_t||tdqs7_a_t\  = M_A_CPU0_SA_DQS_DP<7>
  VSS77  = GND
  DQ22_A  = M_A_CPU0_SA_DQ<22>
  VSS78  = GND
  DQ23_A  = M_A_CPU0_SA_DQ<23>
  VSS79  = GND
  DQ26_A  = M_A_CPU0_SA_DQ<26>
  VSS80  = GND
  DQ27_A  = M_A_CPU0_SA_DQ<27>
  VSS81  = GND
  \dqs8_a_c||tdqs8_a_c\  = M_A_CPU0_SA_DQS_DN<8>
  \dqs8_a_t||tdqs8_a_t\  = M_A_CPU0_SA_DQS_DP<8>
  VSS82  = GND
  DQ30_A  = M_A_CPU0_SA_DQ<30>
  VSS83  = GND
  DQ31_A  = M_A_CPU0_SA_DQ<31>
  VSS84  = GND
  CB2_A  = M_A_CPU0_SA_CB<2>
  VSS85  = GND
  CB3_A  = M_A_CPU0_SA_CB<3>
  VSS86  = GND
  \dqs9_a_c||tdqs9_a_c\  = M_A_CPU0_SA_DQS_DN<9>
  \dqs9_a_t||tdqs9_a_t\  = M_A_CPU0_SA_DQS_DP<9>
  VSS87  = GND
  CB6_A  = M_A_CPU0_SA_CB<6>
  VSS88  = GND
  CB7_A  = M_A_CPU0_SA_CB<7>
  VSS89  = GND
  RESET_N  = RST_M_AB_CPU0_FPGA_N
  VSS90  = GND
  CS1_A_N  = M_A_CPU0_SA_CS_N<3>
  VSS91  = GND
  CA1_A  = M_A_CPU0_SA_CA<1>
  VSS92  = GND
  CA3_A  = M_A_CPU0_SA_CA<3>
  VSS93  = GND
  CA5_A  = M_A_CPU0_SA_CA<5>
  VSS94  = GND
  CK_T  = M_A_CPU0_CLK_DP<1>
  CK_C  = M_A_CPU0_CLK_DN<1>
  VSS95  = GND
  RFU4  = TP_CHA_CPU0_DIMM2_FRU_4
  CA1_B  = M_A_CPU0_SB_CA<1>
  VSS96  = GND
  CA3_B  = M_A_CPU0_SB_CA<3>
  VSS97  = GND
  CA5_B  = M_A_CPU0_SB_CA<5>
  VSS98  = GND
  PAR_B  = M_A_CPU0_SB_PAR
  VSS99  = GND
  CS1_B_N  = M_A_CPU0_SB_CS_N<3>
  VSS100  = GND
  RFU5  = TP_CHA_CPU0_DIMM2_FRU_5
  RFU6  = TP_CHA_CPU0_DIMM2_FRU_6
  VSS101  = GND
  CB6_B  = M_A_CPU0_SB_CB<6>
  VSS102  = GND
  CB7_B  = M_A_CPU0_SB_CB<7>
  VSS103  = GND
  DQS4_B_C  = M_A_CPU0_SB_DQS_DN<4>
  DQS4_B_T  = M_A_CPU0_SB_DQS_DP<4>
  VSS104  = GND
  CB2_B  = M_A_CPU0_SB_CB<2>
  VSS105  = GND
  CB3_B  = M_A_CPU0_SB_CB<3>
  VSS106  = GND
  DQ2_B  = M_A_CPU0_SB_DQ<2>
  VSS107  = GND
  DQ3_B  = M_A_CPU0_SB_DQ<3>
  VSS108  = GND
  \dqs5_b_c||tdqs5_b_c\  = M_A_CPU0_SB_DQS_DN<5>
  \dqs5_b_t||tdqs5_b_t\  = M_A_CPU0_SB_DQS_DP<5>
  VSS109  = GND
  DQ6_B  = M_A_CPU0_SB_DQ<6>
  VSS110  = GND
  DQ7_B  = M_A_CPU0_SB_DQ<7>
  VSS111  = GND
  DQ10_B  = M_A_CPU0_SB_DQ<10>
  VSS112  = GND
  DQ11_B  = M_A_CPU0_SB_DQ<11>
  VSS113  = GND
  \dqs6_b_c||tdqs6_b_c\  = M_A_CPU0_SB_DQS_DN<6>
  \dqs6_b_t||tdqs6_b_t\  = M_A_CPU0_SB_DQS_DP<6>
  VSS114  = GND
  DQ14_B  = M_A_CPU0_SB_DQ<14>
  VSS115  = GND
  DQ15_B  = M_A_CPU0_SB_DQ<15>
  VSS116  = GND
  DQ18_B  = M_A_CPU0_SB_DQ<18>
  VSS117  = GND
  DQ19_B  = M_A_CPU0_SB_DQ<19>
  VSS118  = GND
  \dqs7_b_c||tdqs7_b_c\  = M_A_CPU0_SB_DQS_DN<7>
  \dqs7_b_t||tdqs7_b_t\  = M_A_CPU0_SB_DQS_DP<7>
  VSS119  = GND
  DQ22_B  = M_A_CPU0_SB_DQ<22>
  VSS120  = GND
  DQ23_B  = M_A_CPU0_SB_DQ<23>
  VSS121  = GND
  DQ26_B  = M_A_CPU0_SB_DQ<26>
  VSS122  = GND
  DQ27_B  = M_A_CPU0_SB_DQ<27>
  VSS123  = GND
  \dqs8_b_c||tdqs8_b_c\  = M_A_CPU0_SB_DQS_DN<8>
  \dqs8_b_t||tdqs8_b_t\  = M_A_CPU0_SB_DQS_DP<8>
  VSS124  = GND
  DQ30_B  = M_A_CPU0_SB_DQ<30>
  VSS125  = GND
  DQ31_B  = M_A_CPU0_SB_DQ<31>
  VSS126  = GND
  G1  = GND
  G2  = GND
  G3  = GND

(kicad_pcb
	(version 20260206)
	(generator "pcbnew")
	(generator_version "10.0")
	(general
		(thickness 1.6)
		(legacy_teardrops no)
	)
	(paper "A4")
	(title_block
		(title "03242023_DA0F0TMBIJ0_F0T_Motherboard_J_brd_V01_OCP.brd")
		(comment 1 "Grand Teton / footprint 2856 of 6105 (J2), pads 92-137 of 291")
	)
	(layers
		(0 "F.Cu" signal "TOP")
		(4 "In1.Cu" signal "GND")
		(6 "In2.Cu" signal "IN1")
		(8 "In3.Cu" signal "GND1")
		(10 "In4.Cu" signal "IN2")
		(12 "In5.Cu" signal "GND2")
		(14 "In6.Cu" signal "IN3")
		(16 "In7.Cu" signal "GND3")
		(18 "In8.Cu" signal "VCC")
		(20 "In9.Cu" signal "VCC1")
		(22 "In10.Cu" signal "GND4")
		(24 "In11.Cu" signal "IN4")
		(26 "In12.Cu" signal "GND5")
		(28 "In13.Cu" signal "IN5")
		(30 "In14.Cu" signal "GND6")
		(32 "In15.Cu" signal "IN6")
		(34 "In16.Cu" signal "GND7")
		(2 "B.Cu" signal "BOTTOM")
		(9 "F.Adhes" user "F.Adhesive")
		(11 "B.Adhes" user "B.Adhesive")
		(13 "F.Paste" user "Package Geometry/Pastemask Top")
		(15 "B.Paste" user "Package Geometry/Pastemask Bottom")
		(5 "F.SilkS" user "Ref Des/Silkscreen Top")
		(7 "B.SilkS" user "Ref Des/Silkscreen Bottom")
		(1 "F.Mask" user "Board Geometry/Soldermask Top")
		(3 "B.Mask" user "Board Geometry/Soldermask Bottom")
		(17 "Dwgs.User" user "User.Drawings")
		(19 "Cmts.User" user "User.Comments")
		(21 "Eco1.User" user "User.Eco1")
		(23 "Eco2.User" user "User.Eco2")
		(25 "Edge.Cuts" user "Board Geometry/Outline")
		(27 "Margin" user)
		(31 "F.CrtYd" user "Package Geometry/Place Bound Top")
		(29 "B.CrtYd" user "Package Geometry/Place Bound Bottom")
		(35 "F.Fab" user "Ref Des/Assembly Top")
		(33 "B.Fab" user "Ref Des/Assembly Bottom")
	)
	(footprint ""
		(layer "F.Cu")
		(at 310.937148 -258.091686)
		(property "Reference" "J2"
			(at -3.683 -81.702148 0)
			(unlocked yes)
			(layer "F.SilkS")
			(effects
				(font
					(size 0.7874 0.5842)
					(thickness 0.1524)
				)
				(justify left)
			)
		)
		(property "Value" ""
			(at 0 0 0)
			(layer "F.Fab")
			(effects
				(font
					(size 1.27 1.27)
				)
			)
		)
		(duplicate_pad_numbers_are_jumpers no)
		(pad "92" smd rect
			(at -2.050034 19.12493 270)
			(size 0.519938 1.4986)
			(layers "F.Cu" "F.Mask" "F.Paste")
			(net "GND")
		)
		(pad "93" smd rect
			(at -2.050034 19.975068 270)
			(size 0.519938 1.4986)
			(layers "F.Cu" "F.Mask" "F.Paste")
			(net "M_A_CPU0_SB_DQS_DP<9>")
		)
		(pad "94" smd rect
			(at -2.050034 20.824952 270)
			(size 0.519938 1.4986)
			(layers "F.Cu" "F.Mask" "F.Paste")
			(net "M_A_CPU0_SB_DQS_DN<9>")
		)
		(pad "95" smd rect
			(at -2.050034 21.67509 270)
			(size 0.519938 1.4986)
			(layers "F.Cu" "F.Mask" "F.Paste")
			(net "GND")
		)
		(pad "96" smd rect
			(at -2.050034 22.524974 270)
			(size 0.519938 1.4986)
			(layers "F.Cu" "F.Mask" "F.Paste")
			(net "M_A_CPU0_SB_CB<0>")
		)
		(pad "97" smd rect
			(at -2.050034 23.375112 270)
			(size 0.519938 1.4986)
			(layers "F.Cu" "F.Mask" "F.Paste")
			(net "GND")
		)
		(pad "98" smd rect
			(at -2.050034 24.224996 270)
			(size 0.519938 1.4986)
			(layers "F.Cu" "F.Mask" "F.Paste")
			(net "M_A_CPU0_SB_CB<1>")
		)
		(pad "99" smd rect
			(at -2.050034 25.07488 270)
			(size 0.519938 1.4986)
			(layers "F.Cu" "F.Mask" "F.Paste")
			(net "GND")
		)
		(pad "100" smd rect
			(at -2.050034 25.925018 270)
			(size 0.519938 1.4986)
			(layers "F.Cu" "F.Mask" "F.Paste")
			(net "M_A_CPU0_SB_DQ<0>")
		)
		(pad "101" smd rect
			(at -2.050034 26.774902 270)
			(size 0.519938 1.4986)
			(layers "F.Cu" "F.Mask" "F.Paste")
			(net "GND")
		)
		(pad "102" smd rect
			(at -2.050034 27.62504 270)
			(size 0.519938 1.4986)
			(layers "F.Cu" "F.Mask" "F.Paste")
			(net "M_A_CPU0_SB_DQ<1>")
		)
		(pad "103" smd rect
			(at -2.050034 28.474924 270)
			(size 0.519938 1.4986)
			(layers "F.Cu" "F.Mask" "F.Paste")
			(net "GND")
		)
		(pad "104" smd rect
			(at -2.050034 29.325062 270)
			(size 0.519938 1.4986)
			(layers "F.Cu" "F.Mask" "F.Paste")
			(net "M_A_CPU0_SB_DQS_DP<0>")
		)
		(pad "105" smd rect
			(at -2.050034 30.174946 270)
			(size 0.519938 1.4986)
			(layers "F.Cu" "F.Mask" "F.Paste")
			(net "M_A_CPU0_SB_DQS_DN<0>")
		)
		(pad "106" smd rect
			(at -2.050034 31.025084 270)
			(size 0.519938 1.4986)
			(layers "F.Cu" "F.Mask" "F.Paste")
			(net "GND")
		)
		(pad "107" smd rect
			(at -2.050034 31.874968 270)
			(size 0.519938 1.4986)
			(layers "F.Cu" "F.Mask" "F.Paste")
			(net "M_A_CPU0_SB_DQ<4>")
		)
		(pad "108" smd rect
			(at -2.050034 32.725106 270)
			(size 0.519938 1.4986)
			(layers "F.Cu" "F.Mask" "F.Paste")
			(net "GND")
		)
		(pad "109" smd rect
			(at -2.050034 33.57499 270)
			(size 0.519938 1.4986)
			(layers "F.Cu" "F.Mask" "F.Paste")
			(net "M_A_CPU0_SB_DQ<5>")
		)
		(pad "110" smd rect
			(at -2.050034 34.425128 270)
			(size 0.519938 1.4986)
			(layers "F.Cu" "F.Mask" "F.Paste")
			(net "GND")
		)
		(pad "111" smd rect
			(at -2.050034 35.275012 270)
			(size 0.519938 1.4986)
			(layers "F.Cu" "F.Mask" "F.Paste")
			(net "M_A_CPU0_SB_DQ<8>")
		)
		(pad "112" smd rect
			(at -2.050034 36.124896 270)
			(size 0.519938 1.4986)
			(layers "F.Cu" "F.Mask" "F.Paste")
			(net "GND")
		)
		(pad "113" smd rect
			(at -2.050034 36.975034 270)
			(size 0.519938 1.4986)
			(layers "F.Cu" "F.Mask" "F.Paste")
			(net "M_A_CPU0_SB_DQ<9>")
		)
		(pad "114" smd rect
			(at -2.050034 37.824918 270)
			(size 0.519938 1.4986)
			(layers "F.Cu" "F.Mask" "F.Paste")
			(net "GND")
		)
		(pad "115" smd rect
			(at -2.050034 38.675056 270)
			(size 0.519938 1.4986)
			(layers "F.Cu" "F.Mask" "F.Paste")
			(net "M_A_CPU0_SB_DQS_DP<1>")
		)
		(pad "116" smd rect
			(at -2.050034 39.52494 270)
			(size 0.519938 1.4986)
			(layers "F.Cu" "F.Mask" "F.Paste")
			(net "M_A_CPU0_SB_DQS_DN<1>")
		)
		(pad "117" smd rect
			(at -2.050034 40.375078 270)
			(size 0.519938 1.4986)
			(layers "F.Cu" "F.Mask" "F.Paste")
			(net "GND")
		)
		(pad "118" smd rect
			(at -2.050034 41.224962 270)
			(size 0.519938 1.4986)
			(layers "F.Cu" "F.Mask" "F.Paste")
			(net "M_A_CPU0_SB_DQ<12>")
		)
		(pad "119" smd rect
			(at -2.050034 42.0751 270)
			(size 0.519938 1.4986)
			(layers "F.Cu" "F.Mask" "F.Paste")
			(net "GND")
		)
		(pad "120" smd rect
			(at -2.050034 42.924984 270)
			(size 0.519938 1.4986)
			(layers "F.Cu" "F.Mask" "F.Paste")
			(net "M_A_CPU0_SB_DQ<13>")
		)
		(pad "121" smd rect
			(at -2.050034 43.775122 270)
			(size 0.519938 1.4986)
			(layers "F.Cu" "F.Mask" "F.Paste")
			(net "GND")
		)
		(pad "122" smd rect
			(at -2.050034 44.625006 270)
			(size 0.519938 1.4986)
			(layers "F.Cu" "F.Mask" "F.Paste")
			(net "M_A_CPU0_SB_DQ<16>")
		)
		(pad "123" smd rect
			(at -2.050034 45.47489 270)
			(size 0.519938 1.4986)
			(layers "F.Cu" "F.Mask" "F.Paste")
			(net "GND")
		)
		(pad "124" smd rect
			(at -2.050034 46.325028 270)
			(size 0.519938 1.4986)
			(layers "F.Cu" "F.Mask" "F.Paste")
			(net "M_A_CPU0_SB_DQ<17>")
		)
		(pad "125" smd rect
			(at -2.050034 47.174912 270)
			(size 0.519938 1.4986)
			(layers "F.Cu" "F.Mask" "F.Paste")
			(net "GND")
		)
		(pad "126" smd rect
			(at -2.050034 48.02505 270)
			(size 0.519938 1.4986)
			(layers "F.Cu" "F.Mask" "F.Paste")
			(net "M_A_CPU0_SB_DQS_DP<2>")
		)
		(pad "127" smd rect
			(at -2.050034 48.874934 270)
			(size 0.519938 1.4986)
			(layers "F.Cu" "F.Mask" "F.Paste")
			(net "M_A_CPU0_SB_DQS_DN<2>")
		)
		(pad "128" smd rect
			(at -2.050034 49.725072 270)
			(size 0.519938 1.4986)
			(layers "F.Cu" "F.Mask" "F.Paste")
			(net "GND")
		)
		(pad "129" smd rect
			(at -2.050034 50.574956 270)
			(size 0.519938 1.4986)
			(layers "F.Cu" "F.Mask" "F.Paste")
			(net "M_A_CPU0_SB_DQ<20>")
		)
		(pad "130" smd rect
			(at -2.050034 51.425094 270)
			(size 0.519938 1.4986)
			(layers "F.Cu" "F.Mask" "F.Paste")
			(net "GND")
		)
		(pad "131" smd rect
			(at -2.050034 52.274978 270)
			(size 0.519938 1.4986)
			(layers "F.Cu" "F.Mask" "F.Paste")
			(net "M_A_CPU0_SB_DQ<21>")
		)
		(pad "132" smd rect
			(at -2.050034 53.125116 270)
			(size 0.519938 1.4986)
			(layers "F.Cu" "F.Mask" "F.Paste")
			(net "GND")
		)
		(pad "133" smd rect
			(at -2.050034 53.975 270)
			(size 0.519938 1.4986)
			(layers "F.Cu" "F.Mask" "F.Paste")
			(net "M_A_CPU0_SB_DQ<24>")
		)
		(pad "134" smd rect
			(at -2.050034 54.824884 270)
			(size 0.519938 1.4986)
			(layers "F.Cu" "F.Mask" "F.Paste")
			(net "GND")
		)
		(pad "135" smd rect
			(at -2.050034 55.675022 270)
			(size 0.519938 1.4986)
			(layers "F.Cu" "F.Mask" "F.Paste")
			(net "M_A_CPU0_SB_DQ<25>")
		)
		(pad "136" smd rect
			(at -2.050034 56.524906 270)
			(size 0.519938 1.4986)
			(layers "F.Cu" "F.Mask" "F.Paste")
			(net "GND")
		)
		(pad "137" smd rect
			(at -2.050034 57.375044 270)
			(size 0.519938 1.4986)
			(layers "F.Cu" "F.Mask" "F.Paste")
			(net "M_A_CPU0_SB_DQS_DP<3>")
		)
	)
)
